# S9S_MB_2U (Grand Teton) — schematic netlist excerpt (pin names and nets, part order shuffled) for the footprints in the layout excerpt that follows; sources: Cadence DE-HDL packaged netlist, KiCad conversion of 03242023_DA0F0TMBIJ0_F0T_Motherboard_J_brd_V01_OCP.brd

R4204  Q_RES  1K 1% EMPTY  pkg 0402LF  page 170 : A = P3V3_AUX ; B = U271_1_ADD0
R3934  Q_RES  22 1% CHIP  pkg 0402LF  page 301 : A = HSC_D_OC_R ; B = HSC_D_OC

(kicad_pcb
	(version 20260206)
	(generator "pcbnew")
	(generator_version "10.0")
	(general
		(thickness 1.6)
		(legacy_teardrops no)
	)
	(paper "A4")
	(title_block
		(title "03242023_DA0F0TMBIJ0_F0T_Motherboard_J_brd_V01_OCP.brd")
		(comment 1 "Grand Teton / footprints 2093-2094 of 6105")
	)
	(layers
		(0 "F.Cu" signal "TOP")
		(4 "In1.Cu" signal "GND")
		(6 "In2.Cu" signal "IN1")
		(8 "In3.Cu" signal "GND1")
		(10 "In4.Cu" signal "IN2")
		(12 "In5.Cu" signal "GND2")
		(14 "In6.Cu" signal "IN3")
		(16 "In7.Cu" signal "GND3")
		(18 "In8.Cu" signal "VCC")
		(20 "In9.Cu" signal "VCC1")
		(22 "In10.Cu" signal "GND4")
		(24 "In11.Cu" signal "IN4")
		(26 "In12.Cu" signal "GND5")
		(28 "In13.Cu" signal "IN5")
		(30 "In14.Cu" signal "GND6")
		(32 "In15.Cu" signal "IN6")
		(34 "In16.Cu" signal "GND7")
		(2 "B.Cu" signal "BOTTOM")
		(9 "F.Adhes" user "F.Adhesive")
		(11 "B.Adhes" user "B.Adhesive")
		(13 "F.Paste" user "Package Geometry/Pastemask Top")
		(15 "B.Paste" user "Package Geometry/Pastemask Bottom")
		(5 "F.SilkS" user "Ref Des/Silkscreen Top")
		(7 "B.SilkS" user "Ref Des/Silkscreen Bottom")
		(1 "F.Mask" user "Board Geometry/Soldermask Top")
		(3 "B.Mask" user "Board Geometry/Soldermask Bottom")
		(17 "Dwgs.User" user "User.Drawings")
		(19 "Cmts.User" user "User.Comments")
		(21 "Eco1.User" user "User.Eco1")
		(23 "Eco2.User" user "User.Eco2")
		(25 "Edge.Cuts" user "Board Geometry/Outline")
		(27 "Margin" user)
		(31 "F.CrtYd" user "Package Geometry/Place Bound Top")
		(29 "B.CrtYd" user "Package Geometry/Place Bound Bottom")
		(35 "F.Fab" user "Ref Des/Assembly Top")
		(33 "B.Fab" user "Ref Des/Assembly Bottom")
	)
	(footprint ""
		(layer "F.Cu")
		(at 192.052448 -401.112482)
		(property "Reference" "R3934"
			(at 0 0 0)
			(layer "F.SilkS")
			(hide yes)
			(effects
				(font
					(size 1.27 1.27)
				)
			)
		)
		(property "Value" ""
			(at 0 0 0)
			(layer "F.Fab")
			(effects
				(font
					(size 1.27 1.27)
				)
			)
		)
		(duplicate_pad_numbers_are_jumpers no)
		(fp_line
			(start -0.7874 -0.4064)
			(end 0.7874 -0.4064)
			(stroke
				(width 0.1524)
				(type default)
			)
			(layer "F.SilkS")
		)
		(fp_line
			(start -0.7874 0.4064)
			(end -0.7874 -0.4064)
			(stroke
				(width 0.1524)
				(type default)
			)
			(layer "F.SilkS")
		)
		(fp_line
			(start 0.7874 -0.4064)
			(end 0.7874 0.4064)
			(stroke
				(width 0.1524)
				(type default)
			)
			(layer "F.SilkS")
		)
		(fp_line
			(start 0.7874 0.4064)
			(end -0.7874 0.4064)
			(stroke
				(width 0.1524)
				(type default)
			)
			(layer "F.SilkS")
		)
		(fp_line
			(start -0.67945 -0.305054)
			(end -0.12065 -0.305054)
			(stroke
				(width 0.1)
				(type default)
			)
			(layer "F.Fab")
		)
		(fp_line
			(start -0.67945 0.3048)
			(end -0.67945 -0.305054)
			(stroke
				(width 0.1)
				(type default)
			)
			(layer "F.Fab")
		)
		(fp_line
			(start -0.12065 -0.305054)
			(end -0.12065 -0.2794)
			(stroke
				(width 0.1)
				(type default)
			)
			(layer "F.Fab")
		)
		(fp_line
			(start -0.12065 -0.2794)
			(end 0.12065 -0.2794)
			(stroke
				(width 0.1)
				(type default)
			)
			(layer "F.Fab")
		)
		(fp_line
			(start -0.12065 0.2794)
			(end -0.12065 0.3048)
			(stroke
				(width 0.1)
				(type default)
			)
			(layer "F.Fab")
		)
		(fp_line
			(start -0.12065 0.3048)
			(end -0.67945 0.3048)
			(stroke
				(width 0.1)
				(type default)
			)
			(layer "F.Fab")
		)
		(fp_line
			(start 0.120396 0.2794)
			(end -0.12065 0.2794)
			(stroke
				(width 0.1)
				(type default)
			)
			(layer "F.Fab")
		)
		(fp_line
			(start 0.120396 0.3048)
			(end 0.120396 0.2794)
			(stroke
				(width 0.1)
				(type default)
			)
			(layer "F.Fab")
		)
		(fp_line
			(start 0.12065 -0.3048)
			(end 0.67945 -0.3048)
			(stroke
				(width 0.1)
				(type default)
			)
			(layer "F.Fab")
		)
		(fp_line
			(start 0.12065 -0.2794)
			(end 0.12065 -0.3048)
			(stroke
				(width 0.1)
				(type default)
			)
			(layer "F.Fab")
		)
		(fp_line
			(start 0.67945 -0.3048)
			(end 0.67945 0.3048)
			(stroke
				(width 0.1)
				(type default)
			)
			(layer "F.Fab")
		)
		(fp_line
			(start 0.67945 0.3048)
			(end 0.120396 0.3048)
			(stroke
				(width 0.1)
				(type default)
			)
			(layer "F.Fab")
		)
		(pad "1" smd circle
			(at -0.40005 0)
			(size 0 0)
			(layers "F.Cu" "F.Mask" "F.Paste")
			(net "HSC_D_OC_R")
		)
		(pad "2" smd circle
			(at 0.40005 0)
			(size 0 0)
			(layers "F.Cu" "F.Mask" "F.Paste")
			(net "HSC_D_OC")
		)
	)
	(footprint ""
		(layer "F.Cu")
		(at 297.147234 -16.715994 180)
		(property "Reference" "R4204"
			(at 0 0 180)
			(layer "F.SilkS")
			(hide yes)
			(effects
				(font
					(size 1.27 1.27)
				)
			)
		)
		(property "Value" ""
			(at 0 0 180)
			(layer "F.Fab")
			(effects
				(font
					(size 1.27 1.27)
				)
			)
		)
		(duplicate_pad_numbers_are_jumpers no)
		(fp_line
			(start 0.7874 0.4064)
			(end -0.7874 0.4064)
			(stroke
				(width 0.1524)
				(type default)
			)
			(layer "F.SilkS")
		)
		(fp_line
			(start 0.7874 -0.4064)
			(end 0.7874 0.4064)
			(stroke
				(width 0.1524)
				(type default)
			)
			(layer "F.SilkS")
		)
		(fp_line
			(start -0.7874 0.4064)
			(end -0.7874 -0.4064)
			(stroke
				(width 0.1524)
				(type default)
			)
			(layer "F.SilkS")
		)
		(fp_line
			(start -0.7874 -0.4064)
			(end 0.7874 -0.4064)
			(stroke
				(width 0.1524)
				(type default)
			)
			(layer "F.SilkS")
		)
		(fp_line
			(start 0.67945 0.3048)
			(end 0.120396 0.3048)
			(stroke
				(width 0.1)
				(type default)
			)
			(layer "F.Fab")
		)
		(fp_line
			(start 0.67945 -0.3048)
			(end 0.67945 0.3048)
			(stroke
				(width 0.1)
				(type default)
			)
			(layer "F.Fab")
		)
		(fp_line
			(start 0.12065 -0.2794)
			(end 0.12065 -0.3048)
			(stroke
				(width 0.1)
				(type default)
			)
			(layer "F.Fab")
		)
		(fp_line
			(start 0.12065 -0.3048)
			(end 0.67945 -0.3048)
			(stroke
				(width 0.1)
				(type default)
			)
			(layer "F.Fab")
		)
		(fp_line
			(start 0.120396 0.3048)
			(end 0.120396 0.2794)
			(stroke
				(width 0.1)
				(type default)
			)
			(layer "F.Fab")
		)
		(fp_line
			(start 0.120396 0.2794)
			(end -0.12065 0.2794)
			(stroke
				(width 0.1)
				(type default)
			)
			(layer "F.Fab")
		)
		(fp_line
			(start -0.12065 0.3048)
			(end -0.67945 0.3048)
			(stroke
				(width 0.1)
				(type default)
			)
			(layer "F.Fab")
		)
		(fp_line
			(start -0.12065 0.2794)
			(end -0.12065 0.3048)
			(stroke
				(width 0.1)
				(type default)
			)
			(layer "F.Fab")
		)
		(fp_line
			(start -0.12065 -0.2794)
			(end 0.12065 -0.2794)
			(stroke
				(width 0.1)
				(type default)
			)
			(layer "F.Fab")
		)
		(fp_line
			(start -0.12065 -0.305054)
			(end -0.12065 -0.2794)
			(stroke
				(width 0.1)
				(type default)
			)
			(layer "F.Fab")
		)
		(fp_line
			(start -0.67945 0.3048)
			(end -0.67945 -0.305054)
			(stroke
				(width 0.1)
				(type default)
			)
			(layer "F.Fab")
		)
		(fp_line
			(start -0.67945 -0.305054)
			(end -0.12065 -0.305054)
			(stroke
				(width 0.1)
				(type default)
			)
			(layer "F.Fab")
		)
		(pad "1" smd circle
			(at -0.40005 0 180)
			(size 0 0)
			(layers "F.Cu" "F.Mask" "F.Paste")
			(net "P3V3_AUX")
		)
		(pad "2" smd circle
			(at 0.40005 0 180)
			(size 0 0)
			(layers "F.Cu" "F.Mask" "F.Paste")
			(net "U271_1_ADD0")
		)
	)
)
